# S9S_MB_2U (Grand Teton) — schematic netlist excerpt (pin names and nets, part order shuffled) for the footprints in the layout excerpt that follows; sources: Cadence DE-HDL packaged netlist, KiCad conversion of 03242023_DA0F0TMBIJ0_F0T_Motherboard_J_brd_V01_OCP.brd

PC2336  Q_CAPP  330UF 2.5V +10/-35% EMPTY  pkg SMLF  page 267 : A = PVCCIN_CPU0 ; B = GND
R2802  Q_RES  0 5% CHIP  pkg 0402LF  page 245 : A = HPDB_HSC_PWRGD_R ; B = HPDB_HSC_PWRGD

(kicad_pcb
	(version 20260206)
	(generator "pcbnew")
	(generator_version "10.0")
	(general
		(thickness 1.6)
		(legacy_teardrops no)
	)
	(paper "A4")
	(title_block
		(title "03242023_DA0F0TMBIJ0_F0T_Motherboard_J_brd_V01_OCP.brd")
		(comment 1 "Grand Teton / footprints 5557-5558 of 6105")
	)
	(layers
		(0 "F.Cu" signal "TOP")
		(4 "In1.Cu" signal "GND")
		(6 "In2.Cu" signal "IN1")
		(8 "In3.Cu" signal "GND1")
		(10 "In4.Cu" signal "IN2")
		(12 "In5.Cu" signal "GND2")
		(14 "In6.Cu" signal "IN3")
		(16 "In7.Cu" signal "GND3")
		(18 "In8.Cu" signal "VCC")
		(20 "In9.Cu" signal "VCC1")
		(22 "In10.Cu" signal "GND4")
		(24 "In11.Cu" signal "IN4")
		(26 "In12.Cu" signal "GND5")
		(28 "In13.Cu" signal "IN5")
		(30 "In14.Cu" signal "GND6")
		(32 "In15.Cu" signal "IN6")
		(34 "In16.Cu" signal "GND7")
		(2 "B.Cu" signal "BOTTOM")
		(9 "F.Adhes" user "F.Adhesive")
		(11 "B.Adhes" user "B.Adhesive")
		(13 "F.Paste" user "Package Geometry/Pastemask Top")
		(15 "B.Paste" user "Package Geometry/Pastemask Bottom")
		(5 "F.SilkS" user "Ref Des/Silkscreen Top")
		(7 "B.SilkS" user "Ref Des/Silkscreen Bottom")
		(1 "F.Mask" user "Board Geometry/Soldermask Top")
		(3 "B.Mask" user "Board Geometry/Soldermask Bottom")
		(17 "Dwgs.User" user "User.Drawings")
		(19 "Cmts.User" user "User.Comments")
		(21 "Eco1.User" user "User.Eco1")
		(23 "Eco2.User" user "User.Eco2")
		(25 "Edge.Cuts" user "Board Geometry/Outline")
		(27 "Margin" user)
		(31 "F.CrtYd" user "Package Geometry/Place Bound Top")
		(29 "B.CrtYd" user "Package Geometry/Place Bound Bottom")
		(35 "F.Fab" user "Ref Des/Assembly Top")
		(33 "B.Fab" user "Ref Des/Assembly Bottom")
	)
	(footprint ""
		(layer "B.Cu")
		(at 236.214666 -423.001948 90)
		(property "Reference" "R2802"
			(at 0 0 90)
			(layer "B.SilkS")
			(hide yes)
			(effects
				(font
					(size 1.27 1.27)
				)
				(justify mirror)
			)
		)
		(property "Value" ""
			(at 0 0 90)
			(layer "B.Fab")
			(effects
				(font
					(size 1.27 1.27)
				)
				(justify mirror)
			)
		)
		(duplicate_pad_numbers_are_jumpers no)
		(fp_line
			(start 0.7874 -0.4064)
			(end -0.7874 -0.4064)
			(stroke
				(width 0.1524)
				(type default)
			)
			(layer "B.SilkS")
		)
		(fp_line
			(start -0.7874 -0.4064)
			(end -0.7874 0.4064)
			(stroke
				(width 0.1524)
				(type default)
			)
			(layer "B.SilkS")
		)
		(fp_line
			(start 0.7874 0.4064)
			(end 0.7874 -0.4064)
			(stroke
				(width 0.1524)
				(type default)
			)
			(layer "B.SilkS")
		)
		(fp_line
			(start -0.7874 0.4064)
			(end 0.7874 0.4064)
			(stroke
				(width 0.1524)
				(type default)
			)
			(layer "B.SilkS")
		)
		(fp_line
			(start 0.67945 -0.305054)
			(end 0.12065 -0.305054)
			(stroke
				(width 0.1)
				(type default)
			)
			(layer "B.Fab")
		)
		(fp_line
			(start 0.12065 -0.305054)
			(end 0.12065 -0.2794)
			(stroke
				(width 0.1)
				(type default)
			)
			(layer "B.Fab")
		)
		(fp_line
			(start -0.12065 -0.3048)
			(end -0.67945 -0.3048)
			(stroke
				(width 0.1)
				(type default)
			)
			(layer "B.Fab")
		)
		(fp_line
			(start -0.67945 -0.3048)
			(end -0.67945 0.3048)
			(stroke
				(width 0.1)
				(type default)
			)
			(layer "B.Fab")
		)
		(fp_line
			(start 0.12065 -0.2794)
			(end -0.12065 -0.2794)
			(stroke
				(width 0.1)
				(type default)
			)
			(layer "B.Fab")
		)
		(fp_line
			(start -0.12065 -0.2794)
			(end -0.12065 -0.3048)
			(stroke
				(width 0.1)
				(type default)
			)
			(layer "B.Fab")
		)
		(fp_line
			(start 0.12065 0.2794)
			(end 0.12065 0.3048)
			(stroke
				(width 0.1)
				(type default)
			)
			(layer "B.Fab")
		)
		(fp_line
			(start -0.120396 0.2794)
			(end 0.12065 0.2794)
			(stroke
				(width 0.1)
				(type default)
			)
			(layer "B.Fab")
		)
		(fp_line
			(start 0.67945 0.3048)
			(end 0.67945 -0.305054)
			(stroke
				(width 0.1)
				(type default)
			)
			(layer "B.Fab")
		)
		(fp_line
			(start 0.12065 0.3048)
			(end 0.67945 0.3048)
			(stroke
				(width 0.1)
				(type default)
			)
			(layer "B.Fab")
		)
		(fp_line
			(start -0.120396 0.3048)
			(end -0.120396 0.2794)
			(stroke
				(width 0.1)
				(type default)
			)
			(layer "B.Fab")
		)
		(fp_line
			(start -0.67945 0.3048)
			(end -0.120396 0.3048)
			(stroke
				(width 0.1)
				(type default)
			)
			(layer "B.Fab")
		)
		(pad "1" smd circle
			(at 0.40005 0 270)
			(size 0 0)
			(layers "B.Cu" "B.Mask" "B.Paste")
			(net "HPDB_HSC_PWRGD_R")
		)
		(pad "2" smd circle
			(at -0.40005 0 270)
			(size 0 0)
			(layers "B.Cu" "B.Mask" "B.Paste")
			(net "HPDB_HSC_PWRGD")
		)
	)
	(footprint ""
		(layer "B.Cu")
		(at 336.878676 -330.214224 -90)
		(property "Reference" "PC2336"
			(at 0 0 90)
			(layer "B.SilkS")
			(hide yes)
			(effects
				(font
					(size 1.27 1.27)
				)
				(justify mirror)
			)
		)
		(property "Value" ""
			(at 0 0 90)
			(layer "B.Fab")
			(effects
				(font
					(size 1.27 1.27)
				)
				(justify mirror)
			)
		)
		(duplicate_pad_numbers_are_jumpers no)
		(fp_line
			(start -4.533392 2.249932)
			(end 4.533392 2.249932)
			(stroke
				(width 0.1524)
				(type default)
			)
			(layer "B.SilkS")
		)
		(fp_line
			(start 4.533392 2.249932)
			(end 4.533392 -2.249932)
			(stroke
				(width 0.1524)
				(type default)
			)
			(layer "B.SilkS")
		)
		(fp_line
			(start -4.533392 -2.249932)
			(end -4.533392 2.249932)
			(stroke
				(width 0.1524)
				(type default)
			)
			(layer "B.SilkS")
		)
		(fp_line
			(start 4.533392 -2.249932)
			(end -4.533392 -2.249932)
			(stroke
				(width 0.1524)
				(type default)
			)
			(layer "B.SilkS")
		)
		(fp_rect
			(start 5.39242 2.326132)
			(end 4.533392 -2.326132)
			(stroke
				(width 0)
				(type default)
			)
			(fill yes)
			(layer "B.SilkS")
		)
		(fp_line
			(start -3.750056 2.249932)
			(end 3.750056 2.249932)
			(stroke
				(width 0.1)
				(type default)
			)
			(layer "B.Fab")
		)
		(fp_line
			(start 3.750056 2.249932)
			(end 3.750056 -2.249932)
			(stroke
				(width 0.1)
				(type default)
			)
			(layer "B.Fab")
		)
		(fp_line
			(start -3.750056 -2.249932)
			(end -3.750056 2.249932)
			(stroke
				(width 0.1)
				(type default)
			)
			(layer "B.Fab")
		)
		(fp_line
			(start 3.750056 -2.249932)
			(end -3.750056 -2.249932)
			(stroke
				(width 0.1)
				(type default)
			)
			(layer "B.Fab")
		)
		(fp_text user "-"
			(at -4.619244 1.269746 270)
			(unlocked yes)
			(layer "B.SilkS")
			(effects
				(font
					(size 1.905 1.4224)
					(thickness 0.1524)
				)
				(justify left mirror)
			)
		)
		(fp_text user "+"
			(at 6.322314 0.786384 180)
			(unlocked yes)
			(layer "B.SilkS")
			(effects
				(font
					(size 1.905 1.4224)
					(thickness 0.1524)
				)
				(justify left mirror)
			)
		)
		(fp_text user "+"
			(at 6.322314 0.786384 180)
			(unlocked yes)
			(layer "B.Fab")
			(effects
				(font
					(size 1.905 1.4224)
					(thickness 0.1524)
				)
				(justify left mirror)
			)
		)
		(fp_text user "-"
			(at -4.8514 -0.14605 270)
			(unlocked yes)
			(layer "B.Fab")
			(effects
				(font
					(size 1.905 1.4224)
					(thickness 0.1524)
				)
				(justify left mirror)
			)
		)
		(pad "1" smd rect
			(at 3.199892 0 90)
			(size 2.413 2.8194)
			(layers "B.Cu" "B.Mask" "B.Paste")
			(net "PVCCIN_CPU0")
		)
		(pad "2" smd rect
			(at -3.199892 0 90)
			(size 2.413 2.8194)
			(layers "B.Cu" "B.Mask" "B.Paste")
			(net "GND")
		)
	)
)
